M48
INCH,TZ
T01C.01
T02C.012
T03C.016
T04C.028
T05C.032
T06C.036
T07C.091
T08C.224
T09C.052
T10C.086
;LEADER: 12 
;HEADER: 
;CODE  : ASCII 
;FILE  : 16369-sd-1-4.drl for board 16369-sd.brd ... layers TOP and BOTTOM
;T01 Holesize 1. = 10.000000 Tolerance = +0.000000/-0.000000 PLATED MILS Quantity = 174
;T02 Holesize 2. = 12.000000 Tolerance = +0.000000/-0.000000 PLATED MILS Quantity = 66
;T03 Holesize 3. = 16.000000 Tolerance = +0.000000/-0.000000 PLATED MILS Quantity = 8
;T04 Holesize 4. = 28.000000 Tolerance = +0.000000/-0.000000 PLATED MILS Quantity = 22
;T05 Holesize 5. = 32.000000 Tolerance = +0.000000/-0.000000 PLATED MILS Quantity = 4
;T06 Holesize 6. = 36.000000 Tolerance = +0.000000/-0.000000 PLATED MILS Quantity = 12
;T07 Holesize 7. = 91.000000 Tolerance = +0.000000/-0.000000 PLATED MILS Quantity = 8
;T08 Holesize 8. = 224.000000 Tolerance = +0.000000/-0.000000 PLATED MILS Quantity = 1
;T09 Holesize 9. = 52.000000 Tolerance = +0.000000/-0.000000 NON_PLATED MILS Quantity = 2
;T10 Holesize 10. = 86.000000 Tolerance = +0.000000/-0.000000 NON_PLATED MILS Quantity = 13
%
G90
T01
X36900Y17600
X39400Y41000
X26000Y51600
X35744Y51944
X33200Y59100
X33100Y73900
X37100Y73960
X9000Y77250
Y81250
X37500Y87300
X17700Y89400
X32200Y91400
X19763Y92200
X23093Y99967
X27200Y104100
X34900Y106742
X22800Y112600
X32100Y114900
X24000Y120900
X9581Y160069
X20539Y163381
X15007Y163581
X11840Y177692
X16253Y180320
X15857Y202417
X17100Y278300
X13650Y278350
X26270Y282547
X22820Y282597
X4100Y294900
X4200Y312100
Y329000
X29000Y338600
X18600Y338800
X20100Y350300
X4400
X60400
X44000Y350200
X42800Y338500
X60300Y331800
X60500Y316400
X60400Y305900
X60300Y290000
X47300Y168700
X51400Y168300
X55700Y121400
X50400Y118300
X42500Y115000
X46200Y111200
X47300Y107940
X41492Y106258
X75600Y91500
X40900Y88400
X75600Y87000
X79604Y86869
X40000Y77100
X79750Y76600
X75100Y63900
X43900Y59600
X73000Y57200
X58700Y55600
X42300Y51900
X69446Y48262
X79000Y43600
X55500Y42000
X48000Y38000
X63300Y37300
X41000Y36900
X57450Y35400
X50100Y34500
X57400Y26400
X70360Y25750
X50100Y20700
X76900Y15500
X68838Y12300
X73838Y12100
X82200Y60800
X100100Y56300
X118100Y45000
X97200Y44150
X114900Y39900
X97500Y36600
X119200Y30900
X97400Y29300
X99300Y25700
X104900Y21400
X126742Y15658
X124300Y22600
X125700Y26500
X132600Y29600
X136439Y31761
X132500Y41200
X132600Y53800
X154444Y72036
X156891Y79378
X159711Y82091
X186200Y14900
X163452Y32350
X179093Y38185
X179500Y42750
X163000Y43800
X172800Y44950
X182800Y46500
X161300Y51500
X174300Y52000
X194560Y53277
Y56777
X178843Y59000
X169750Y62500
X188250Y66000
X160800Y72000
X192500Y73385
X192691Y84234
X160794Y86162
X174600Y86980
X171263Y92837
X198100Y104000
X184900Y106300
X190900Y112200
X184700Y112500
X193500Y135835
X172300Y337600
X193300Y337900
X188300Y343400
X172300Y350200
X188000Y350300
X209500
X228400Y350200
X222500Y344500
X200200Y343900
X211900Y337500
X228500Y337100
X219900Y330500
X214200Y325100
X227800Y322200
X224000Y306000
X220550Y306050
X214401Y281884
X215411Y270499
X215916Y232222
X209506Y229990
X207750Y224016
X214119Y216661
X219269Y216635
X224000Y210584
X220200Y151000
X211000Y140500
X218700Y132335
X214800Y128309
X210276Y122000
X204818Y118400
X214500Y112000
X218350Y111900
X219000Y107560
Y104060
X228600Y85900
X204340Y71660
X228600Y69200
X208900Y59000
X222609Y53150
X220732Y46039
X207293Y45526
X228600Y42000
X222500Y35100
X218300Y32700
X211900Y24800
X228400Y22800
X203300Y14800
X217800Y14300
X208500Y9400
X228300Y6100
X219300Y-13900
X228400Y-21400
X208500Y-22000
T02
X6000Y-17500
X16090Y-6960
Y-3360
Y240
Y3840
X4100Y12300
X4300Y38700
X21000Y53500
X4629Y64843
X20200Y116600
X22383Y128937
X42600Y129000
X22598Y150420
X44100Y154167
X56400Y158800
X51500Y187600
X26700Y189160
X51500Y191500
X51400Y195600
X56755Y199384
X51076Y202657
X6220Y219509
X4333Y242011
X5244Y259114
X55200Y285022
X65600Y128100
X70600Y122500
X76100Y117800
X81634Y111544
X87600Y106400
X101600Y99700
X94193Y99637
X97600Y92200
X98000Y68200
X102000Y62400
X112900Y51800
X78838Y11602
X63938Y11580
X168858Y12000
X140100Y14000
X134800Y60300
X135800Y70800
X135900Y99400
X124300Y99500
X146700Y108400
X154700Y116500
X178747Y288699
X182347Y292152
X199557Y292020
X199521Y288390
X220678Y284412
X205848Y199637
X222450Y199500
X218700Y193900
X186100Y186500
X222800Y182000
X219150Y178000
X199600Y156500
X202783Y128937
X190700Y127400
X215400Y88900
X212287Y39469
X217340Y3840
Y240
Y-3360
Y-6960
T03
X96200Y16400
X107506Y16719
X116430Y16569
X133200Y17751
X16977Y244294
X16984Y248748
X191391Y278906
X195939Y278959
T04
X12598Y312992
X28346Y250000
Y240157
Y232283
Y222440
X38189Y220472
Y228346
Y236220
Y244094
Y251968
X51968Y312992
X172835
X188583Y250000
Y240157
Y232283
Y222440
X198426Y220472
Y228346
Y236220
Y244094
Y251968
X212205Y312992
T05
X27283Y173228
X37283
X183583
X193583
T06
X32283Y303149
X42126
X22440
X32283Y322835
X42126
X22440
X182677Y303149
X192520
X202363
X192520Y322835
X182677
X202363
T07
X24409Y211023
X40157
X24409Y261417
X40157
X184646
X200394
Y211023
X184646
T08
X116339Y78740
T09
X41752Y5118
X190926
T10
X365520Y-1413
X-18898Y16741
X13800Y60400
X114497Y137176
X366606Y190776
X365520Y387169
X218800Y337200
X115583Y329366
X114497Y525759
X366606Y579359
X494816Y713716
X115583Y717948
X-17506Y723144
M30
